# SCM (Grand Teton) — schematic parts with pin connectivity, parts 1377–1395 of 1428; source: Cadence DE-HDL packaged netlist (pstxprt.dat, pstxnet.dat, pstchip.dat)

U21  IDTQS3VH257PAG  IC  pkg SMLF  page 44
  1  S  IN  = FM_BMC_BIOS_MUX_CS_SPI_R_SEL_0
  2  I_0A  BI  = SPI_SYS_MUX_WP_IO2
  3  I_1A  BI  = SPI_BMC_BIOS_ROM_R_IO2
  4  YA  BI  = SPI_PCH_MUXED_IO2
  5  I_0B  BI  = SPI_SYS_MUX_MISO
  6  I_1B  BI  = SPI_BMC_BIOS_ROM_R_MISO
  7  YB  BI  = SPI_PCH_MUXED_IO1
  8  GND  POWER  = GND
  9  YC  BI  = SPI_PCH_MUXED_CS0_N
  10  I_1C  BI  = SPI_BMC_BIOS_SOURCE_CS0_N
  11  I_0C  BI  = SPI_PCH_SECURE_CS0_N
  12  YD  BI  = TP_BIOS_MUX1_PIN12
  13  I_1D  BI  = TP_BIOS_MUX1_PIN13
  14  I_0D  BI  = TP_BIOS_MUX1_PIN14
  15  \e*\  IN  = PD_BIOS_MUX_EN_N
  16  VCC  POWER  = P3V3_AUX

U22  PI3PCIE3212ZBEX  IC  pkg QFN20_TH_0-5_2-5X4-5  page 29
  1  VDD0  POWER  = P3V3_AUX
  2  PD  IN  = USB3_MUX_PD
  3  A0_P  BI  = USB3_01_MUX_FB_TXP
  4  A0_N  BI  = USB3_01_MUX_FB_TXN
  5  GND1  POWER  = GND
  6  VDD1  POWER  = P3V3_AUX
  7  A1_P  BI  = USB3_01_MUX_FB_RXP
  8  A1_N  BI  = USB3_01_MUX_FB_RXN
  9  SEL  IN  = DEBUG_PORT_PRSNT
  10  VDD2  POWER  = P3V3_AUX
  11  GND2  POWER  = GND
  12  C1_N  BI  = SMB_DEBUG_AUX_LVC3_USB_R2_SCL
  13  C1_P  BI  = SMB_DEBUG_AUX_LVC3_USB_R2_SDA
  14  C0_N  BI  = DEBUG_PORT_UART_TX
  15  C0_P  BI  = DEBUG_PORT_UART_RX
  16  B1_N  BI  = USB3_FPNL_RXN
  17  B1_P  BI  = USB3_FPNL_RXP
  18  B0_N  BI  = USB3_01_TXN_C
  19  B0_P  BI  = USB3_01_TXP_C
  20  GND0  POWER  = GND
  TH  TH  POWER  = NC

U23  74LVC1G07W57  74LVC1G07W5-7 IC  pkg SOT25-5_0-95_3X1-6  page 28
  1  NC1  TRI  = NC
  2  A  IN  = DEBUG_PORT_PRSNT
  3  GND  POWER  = GND
  4  Y  OCA  = DEBUG_PORT_PRSNT_BUF_R_EN
  5  VCC  POWER  = P3V3_AUX

U24  74LVC2G07DW7  74LVC2G07DW-7 IC  pkg SOT363_0-65_2X1-25XC  page 30
  1  \1a\  IN  = UART_BMC_5_TXD_BUF1_R
  2  GND  POWER  = GND
  3  \2a\  IN  = UART_BMC_5_RXD_BUF
  4  \2y\  OUT  = UART_BMC_5_RXD_BUF_R
  5  VCC  POWER  = P3V3_AUX
  6  \1y\  OUT  = UART_BMC_5_TXD_BUF

U25  LCMXO3LF2100C5BG256C  LCMXO3LF-2100C-5BG256C IC  pkg BGA256_0-8_14X14  page 34
  A1  VCC_A1  POWER  = PVCCA_AUX_PLD
  A2  NC1  TRI  = NC
  A3  PT11C  BI  = BSM_PRSNT_R1_N
  A4  PT10A  BI  = RST_PLTRST_R1_N
  A5  PT11A  BI  = RST_RSMRST_N
  A6  \pt12d||tdi\  BI  = JTAG_SCM_PLD_TDI
  A7  \pt16c||tck\  BI  = JTAG_SCM_PLD_TCK
  A8  \pt17b||pclkc0_1\  BI  = IRQ_BMC_PCH_NMI_R_N
  A9  \pt18c||scl||pclkt0_0\  BI  = SMB_BMC_MM16_R3_SCL
  A10  PT19B  BI  = NC
  A11  PT21A  BI  = RST_EXTRST_R_N
  A12  PT22B  BI  = FM_ADR_COMPLETE
  A13  \pt24c||initn\  BI  = PU_FPGA_NSTATUS
  A14  PT22D  BI  = SGPIO_CLK_PLD_0
  A15  PT24B  BI  = FM_THERMTRIP_DLY_LVC1_R_N
  A16  VCC_A16  POWER  = PVCCA_AUX_PLD
  B1  PL1C  BI  = NC
  B2  GND_B2  POWER  = GND
  B3  PT9C  BI  = IRQ_BMC_CPU_NMI_R
  B4  PT11D  BI  = RST_PCA9548_SENSOR_N
  B5  PT9B  BI  = FM_TPM_PRSNT_1_R_N
  B6  PT11B  BI  = FM_JTAG_BMC_MUX_SEL_R2
  B7  PT13A  BI  = IRQ_UV_DETECT_N
  B8  \pt16d||tms\  BI  = JTAG_SCM_PLD_TMS
  B9  PT19A  BI  = IRQ_PCH_SCI_WHEA_N
  B10  \pt20d||programn\  BI  = PU_PT20D
  B11  PT22A  BI  = IRQ_OC_DETECT_N
  B12  PT23B  BI  = SGPIO_PLD_LD_0
  B13  PT22C  BI  = IRQ_OC_DETECT_EN_N
  B14  PT24A  BI  = SGPIO_PLD_DI_0
  B15  GND_B15  POWER  = GND
  B16  PR1D  BI  = FM_PECI_SEL_N
  C1  PL2C  BI  = NC
  C2  PL1D  BI  = NC
  C3  GND_C3  POWER  = GND
  C4  PT9A  BI  = FM_TPM_PRSNT_0_R_N
  C5  PT10B  BI  = PWRGD_PSU_AC_PWROK_PLD
  C6  \pt12c||tdo\  BI  = JTAG_SCM_PLD_TDO
  C7  PT13B  BI  = RST_BMC_RSTBTN_OUT_N
  C8  \pt17a||pclkt0_1\  BI  = CLK_25M_OSC_FPGA
  C9  \pt18d||sda||pclkc0_0\  BI  = SMB_BMC_MM16_R3_SDA
  C10  \pt20c||jtagenb\  BI  = JTAG_SCM_PLD_R_JTAGEN
  C11  PT21B  BI  = PWRGD_CPUPWRGD_LVC1
  C12  PT23A  BI  = SGPIO_PLD_DO_0
  C13  \pt24d||done\  BI  = PU_FPGA_CONFIG_DONE
  C14  GND_C14  POWER  = GND
  C15  PR1C  BI  = VOL_SEN_ALERT_R
  C16  PR2C  BI  = SMB_BMC_ALERT3_R1_N
  D1  \pl1b||l_gpllc_fb\  BI  = NC
  D2  PL2D  BI  = NC
  D3  \pl1a||l_gpllt_fb\  BI  = NC
  D4  GND_D4  POWER  = GND
  D5  VCCIO0_D5  POWER  = VCCIO0
  D6  PT12A  BI  = FM_BMC_DBP_PRESENT_N
  D7  PT13D  BI  = FM_ME_BT_DONE
  D8  PT17C  BI  = FM_PCH_BMC_THERMTRIP_N
  D9  PT18B  BI  = NC
  D10  PT20A  BI  = NC
  D11  PT21D  BI  = IRQ_CPU1_VRHOT_N
  D12  VCCIO0_D12  POWER  = VCCIO0
  D13  GND_D13  POWER  = GND
  D14  PR1A  BI  = H_CPU0_MEMTRIP_LVC1_N
  D15  PR2D  BI  = SMB_BMC_ALERT4_R1_N
  D16  PR2A  BI  = H_CPU1_MEMTRIP_LVC1_N
  E1  \pl3a||pclkt5_0\  BI  = NC
  E2  \pl2a||l_gpllt_in\  BI  = NC
  E3  \pl2b||l_gpllc_in\  BI  = NC
  E4  VCCIO5  POWER  = VCCIO5
  E5  GND_E5  POWER  = GND
  E6  PT13C  BI  = BMC_CPLD_GPIO_2_R2
  E7  PT12B  BI  = PWRGD_PCH_PWROK
  E8  PT16B  BI  = FM_BIOS_POST_CMPLT_BMC_N
  E9  PT17D  BI  = H_CPU1_PROCHOT_LVC1_R_N
  E10  PT20B  BI  = FM_CPU_MSMI_CATERR_LVT3_PLD_N
  E11  PT19D  BI  = TP_PLD_19D
  E12  GND_E12  POWER  = GND
  E13  VCCIO1_E13  POWER  = VCCIO1
  E14  PR2B  BI  = IRQ_SGPIO_R_N
  E15  PR1B  BI  = FM_SPD_REMOTE_EN_R
  E16  PR3A  BI  = RST_SGPIO_RESET_R_N
  F1  PL4B  BI  = NC
  F2  \pl3b||pclkc5_0\  BI  = NC
  F3  PL4A  BI  = NC
  F4  PL3C  BI  = NC
  F5  PL5C  BI  = NC
  F6  GND_F6  POWER  = GND
  F7  PT16A  BI  = FM_PCIE_M2_SSD0_PRSNT_N
  F8  PT18A  BI  = RST_SRST_PLD_BMC_R2_N
  F9  PT19C  BI  = NC
  F10  PT21C  BI  = IRQ_CPU0_VRHOT_N
  F11  GND_F11  POWER  = GND
  F12  PR4C  BI  = TP_PLD_L3
  F13  PR3C  BI  = SMB_BMC_ALERT9_R1_N
  F14  PR4A  BI  = BMC_CPLD_GPIO_8_R2
  F15  PR3B  BI  = BMC_CPLD_GPIO_7_R2
  F16  PR4B  BI  = NC
  G1  PL6A  BI  = NC
  G2  PL5A  BI  = NC
  G3  PL5B  BI  = NC
  G4  PL4D  BI  = NC
  G5  PL4C  BI  = NC
  G6  PL3D  BI  = NC
  G7  VCC_G7  POWER  = PVCCA_AUX_PLD
  G8  VCCIO0_G8  POWER  = VCCIO0
  G9  VCCIO0_G9  POWER  = VCCIO0
  G10  VCC_G10  POWER  = PVCCA_AUX_PLD
  G11  PR5C  BI  = FM_SLPS3_GF_R_N
  G12  PR3D  BI  = SMB_BMC_ALERT10_R1_N
  G13  PR4D  BI  = RST_BMC_SELF_HW_R2
  G14  PR5B  BI  = NC
  G15  PR5A  BI  = NC
  G16  PR6A  BI  = BMC_CPLD_GPIO_12_R2
  H1  PL7B  BI  = NC
  H2  PL6B  BI  = NC
  H3  PL7A  BI  = NC
  H4  PL6C  BI  = NC
  H5  PL9C  BI  = NC
  H6  PL5D  BI  = NC
  H7  VCCIO4_H7  POWER  = VCCIO4
  H8  GND_H8  POWER  = GND
  H9  GND_H9  POWER  = GND
  H10  VCCIO1_H10  POWER  = VCCIO1
  H11  PR9C  BI  = RST_MB_STBY_R_N
  H12  PR5D  BI  = RST_ROT_CPU_R_N
  H13  PR6C  BI  = FM_ESPI_PLD_R_EN
  H14  \pr7a||pclkt1_0\  BI  = NC
  H15  PR6B  BI  = BMC_CPLD_GPIO_13_R2
  H16  \pr7b||pclkc1_0\  BI  = NC
  J1  \pl7c||pclkt4_0\  BI  = NC
  J2  PL9A  BI  = NC
  J3  \pl7d||pclkc4_0\  BI  = NC
  J4  PL9D  BI  = NC
  J5  PL10C  BI  = NC
  J6  PL6D  BI  = NC
  J7  VCCIO4_J7  POWER  = VCCIO4
  J8  GND_J8  POWER  = GND
  J9  GND_J9  POWER  = GND
  J10  VCCIO1_J10  POWER  = VCCIO1
  J11  PR10C  BI  = NC
  J12  PR6D  BI  = FM_THROTTLE_R_N
  J13  PR9D  BI  = FM_ADR_TRIGGER_N
  J14  PR7D  BI  = H_CPU0_PROCHOT_LVC1_R_N
  J15  PR9A  BI  = RST_BMC_HW_R
  J16  PR7C  BI  = FM_PMBUS_ALERT_EN
  K1  PL9B  BI  = NC
  K2  PL10B  BI  = NC
  K3  PL10A  BI  = NC
  K4  PL11C  BI  = NC
  K5  PL12C  BI  = NC
  K6  PL10D  BI  = NC
  K7  VCC_K7  POWER  = PVCCA_AUX_PLD
  K8  VCCIO2_K8  POWER  = VCCIO2
  K9  VCCIO2_K9  POWER  = VCCIO2
  K10  VCC_K10  POWER  = PVCCA_AUX_PLD
  K11  PR12C  BI  = FM_PCHHOT_R_N
  K12  PR11D  BI  = FM_BIOS_DEBUG_EN_N
  K13  PR11C  BI  = FM_BMC_READY_PLD_N
  K14  PR10A  BI  = FM_PWR_R_BTN
  K15  PR10B  BI  = PWRGD_SYS_PWROK_PLD
  K16  PR9B  BI  = NC
  L1  PL11A  BI  = NC
  L2  \pl12a||pclkt3_0\  BI  = NC
  L3  PL11B  BI  = NC
  L4  PL12D  BI  = NC
  L5  PL11D  BI  = NC
  L6  GND_L6  POWER  = GND
  L7  PB8D  BI  = NC_FM_PFR_NO_SERVICE_ACT_N
  L8  PB11D  BI  = FM_PFR_DSW_PWROK_N
  L9  PB12D  BI  = FM_BMC_CPU_FBRK_OUT_R_N
  L10  PB18D  BI  = FM_UARTSW_MSB_R_N
  L11  GND_L11  POWER  = GND
  L12  PR10D  BI  = FM_BMC_EN_DET_R
  L13  PR12D  BI  = FM_BMC_ONCTL_R_N
  L14  PR11B  BI  = SMB_BMC_ALERT12_N
  L15  PR12A  BI  = NC
  L16  PR11A  BI  = USB_OC0_REAR_R_N
  M1  \pl12b||pclkc3_0\  BI  = NC
  M2  PL14A  BI  = NC
  M3  PL13A  BI  = NC
  M4  VCCIO3  POWER  = VCCIO3
  M5  GND_M5  POWER  = GND
  M6  PB11C  BI  = BMC_MONITER
  M7  PB9C  BI  = CLK_GEN2_BMC_RC_OE_N
  M8  PB16C  BI  = PWRGD_P1V8_AUX_R1
  M9  PB18C  BI  = FM_UARTSW_LSB_R_N
  M10  PB21C  BI  = PU_FPGA_NCONFIG
  M11  PB19D  BI  = NC
  M12  GND_M12  POWER  = GND
  M13  VCCIO1_M13  POWER  = VCCIO1
  M14  PR13A  BI  = PWR_LED_CPLD
  M15  PR13B  BI  = PWRGD_P5V_AUX_R1
  M16  PR12B  BI  = NC
  N1  PL13B  BI  = NC
  N2  PL13C  BI  = NC
  N3  PL14B  BI  = NC
  N4  GND_N4  POWER  = GND
  N5  VCCIO2_N5  POWER  = VCCIO2
  N6  PB8C  BI  = FM_BMC_DEBUG_SW_R2_N
  N7  PB9D  BI  = IRQ_SML0_ALERT_R_N
  N8  PB12C  BI  = CLK_BUF1_GPU_FPGA_OE_R_N
  N9  PB16D  BI  = PWRGD_P3V3_RGM_R1
  N10  PB19C  BI  = NC
  N11  PB21D  BI  = NC
  N12  VCCIO2_N12  POWER  = VCCIO2
  N13  GND_N13  POWER  = GND
  N14  PR14B  BI  = PWRGD_P2V5_AUX_R1
  N15  PR13C  BI  = AC_PWR_BTN_R2_N
  N16  PR14A  BI  = PWRGD_P3V3_AUX_R1
  P1  PL13D  BI  = NC
  P2  PL14D  BI  = NC
  P3  GND_P3  POWER  = GND
  P4  PB3A  BI  = FM_P12V_HSC_ENABLE_R2
  P5  PB5B  BI  = TP_PLD_C13
  P6  \pb8a||mclk||cclk\  BI  = FM_HDD_LED_N
  P7  PB9B  BI  = GPU_WP_HW_CTRL_R_N
  P8  PB12A  BI  = GPU_FPGA_RST_N
  P9  \pb16b||pclkc2_1\  BI  = PWRGD_P1V0_AUX_R1
  P10  PB19A  BI  = NC
  P11  PB21B  BI  = NC
  P12  PB24A  BI  = NC
  P13  \pb25b||si||sispi\  BI  = NC
  P14  GND_P14  POWER  = GND
  P15  PR14C  BI  = NC
  P16  PR13D  BI  = NC
  R1  PL14C  BI  = NC
  R2  GND_R2  POWER  = GND
  R3  PB3D  BI  = PWRGD_DSW_PWROK_R2
  R4  PB6D  BI  = FM_BMC_SUSACK_R2_N
  R5  \pb5a||csspin\  BI  = FM_DEBUG_PORT_R2_PRSNT_N
  R6  PB6B  BI  = FM_BMC_CRASHLOG_TRIG_R2_N
  R7  PB9A  BI  = GPU_NVS_PWR_BRAKE_R_N
  R8  \pb11b||pclkc2_0\  BI  = NC_FM_PFR_UPDATE_N
  R9  PB18A  BI  = NC
  R10  PB19B  BI  = NC
  R11  PB22A  BI  = NC
  R12  \pb25a||sn\  BI  = PU_PB25A
  R13  PB22C  BI  = NC
  R14  PB25D  BI  = SMB_BMC_MM16_R4_SDA
  R15  GND_R15  POWER  = GND
  R16  PR14D  BI  = SMB_BMC_ALERT16_R2_N
  T1  VCC_T1  POWER  = PVCCA_AUX_PLD
  T2  PB3C  BI  = FM_SOL_UART_CH_SEL_R2
  T3  PB6C  BI  = RST_WDTRST_PLD_R2_N
  T4  PB3B  BI  = NC
  T5  PB6A  BI  = IRQ_PCH_TPM_SPI_R2_N
  T6  \pb8b||so||spiso\  BI  = FM_PCH_BEEP_LED
  T7  \pb11a||pclkt2_0\  BI  = RST_PFR_OVR_RTC_R
  T8  PB12B  BI  = FM_JTAG_TCK_MUX_BMC_SEL
  T9  \pb16a||pclkt2_1\  BI  = PWRGD_P1V2_AUX_R1
  T10  PB18B  BI  = NC
  T11  PB21A  BI  = NC
  T12  PB22B  BI  = NC
  T13  PB24B  BI  = NC
  T14  PB22D  BI  = NC
  T15  PB25C  BI  = SMB_BMC_MM16_R4_SCL
  T16  VCC_T16  POWER  = PVCCA_AUX_PLD

U26  74HC1G126GW  IC  pkg TSSOP5_0-65_2-05X1-25  page 23
  1  \1\  IN  = BMC_DDC_BUF_EN
  2  \2\  IN  = V_VGAVS
  3  GND  POWER  = GND
  4  \4\  TRI  = V_VGAVS_BUF_R
  5  \5\  POWER  = BMC_DDC_BUF_PWR

U27  DT1240E04LP7  DT1240E-04LP-7 IC  pkg U-DFN2510-10_0-5_2-5X1  page 29
  1  IO1  BI  = USB3_01_FB_TXP
  2  IO2  BI  = USB3_01_FB_TXN
  3  VSS1  POWER  = GND
  4  IO3  BI  = USB3_01_FB_RXP
  5  IO4  BI  = USB3_01_FB_RXN
  6  NC1  TRI  = USB3_01_FB_RXN
  7  NC2  TRI  = USB3_01_FB_RXP
  8  VSS2  POWER  = GND
  9  NC3  TRI  = USB3_01_FB_TXN
  10  NC4  TRI  = USB3_01_FB_TXP

U28  74LVC1G66GV  IC  pkg SC74AXA  page 13
  1  Y  BI  = RMII_OCP_RCLKI
  2  Z  BI  = RMII_OCP_RCLKI_ISO
  3  GND  POWER  = GND
  4  E  IN  = PWRGD_P1V0_AUX_DELAY_R
  5  VCC  POWER  = P3V3_LDO

U29  74HC1G126GW  IC  pkg TSSOP5_0-65_2-05X1-25  page 29
  1  \1\  IN  = DEBUG_PORT_PRSNT
  2  \2\  IN  = SPA_SOUT_SW_DBG
  3  GND  POWER  = GND
  4  \4\  TRI  = DEBUG_PORT_UART_TX
  5  \5\  POWER  = P3V3_AUX

U30  IDTQS3VH257PAG  IC  pkg SMLF  page 44
  1  S  IN  = FM_BMC_BIOS_MUX_CS_SPI_R_SEL_0
  2  I_0A  BI  = SPI_SYS_MUX_MOSI
  3  I_1A  BI  = SPI_BMC_BIOS_ROM_R_MOSI
  4  YA  BI  = SPI_PCH_MUXED_IO0
  5  I_0B  BI  = SPI_SYS_MUX_HOLD_IO3
  6  I_1B  BI  = SPI_BMC_BIOS_ROM_R_IO3
  7  YB  BI  = SPI_PCH_MUXED_IO3
  8  GND  POWER  = GND
  9  YC  BI  = SPI_PCH_MUXED_CLK
  10  I_1C  BI  = SPI_BMC_BIOS_ROM_R_CLK
  11  I_0C  BI  = SPI_SYS_MUX_CLK
  12  YD  BI  = TP_BIOS_MUX0_PIN12
  13  I_1D  BI  = TP_BIOS_MUX0_PIN13
  14  I_0D  BI  = TP_BIOS_MUX0_PIN14
  15  \e*\  IN  = PD_BIOS_MUX_EN_N
  16  VCC  POWER  = P3V3_AUX

U31  74LVC1G07GW  IC  pkg SOT353_Q  page 50
  1  NC  TRI  = TP_PWR_BUF
  2  A  IN  = REAR_PWR_BTN_N
  3  GND  POWER  = GND
  4  Y  OCA  = PWR_BTN_BMC_N
  5  VCC  POWER  = P3V3_AUX

U32  74LVC1G17GW  IC  pkg TSSOP5  page 50
  1  NC  TRI  = TP_ID_BUF
  2  A  IN  = REAR_ID_RST_BTN_N
  3  GND  POWER  = GND
  4  Y  OCA  = ID_RST_BTN_BMC_N
  5  VCC  POWER  = P3V3_AUX

U33  74HC1G126GW  IC  pkg TSSOP5_0-65_2-05X1-25  page 23
  1  \1\  IN  = BMC_DDC_BUF_EN
  2  \2\  IN  = V_VGAHS
  3  GND  POWER  = GND
  4  \4\  TRI  = V_VGAHS_BUF_R
  5  \5\  POWER  = BMC_DDC_BUF_PWR

U34  DT1240E04LP7  DT1240E-04LP-7 IC  pkg U-DFN2510-10_0-5_2-5X1  page 23
  1  IO1  BI  = V_BMC_LS_DDC_SCL_R
  2  IO2  BI  = V_BMC_LS_DDC_SDA_R
  3  VSS1  POWER  = GND
  4  IO3  BI  = V_VGAHS_BUF
  5  IO4  BI  = V_VGAVS_BUF
  6  NC1  TRI  = V_VGAVS_BUF
  7  NC2  TRI  = V_VGAHS_BUF
  8  VSS2  POWER  = GND
  9  NC3  TRI  = V_BMC_LS_DDC_SDA_R
  10  NC4  TRI  = V_BMC_LS_DDC_SCL_R

U35  DT1240E04LP7  DT1240E-04LP-7 IC  pkg U-DFN2510-10_0-5_2-5X1  page 23
  1  IO1  BI  = V_DACB_IO
  2  IO2  BI  = V_DACG_IO
  3  VSS1  POWER  = GND
  4  IO3  BI  = V_DACR_IO
  5  IO4  BI  = TP4
  6  NC1  TRI  = TP_ESD_VGA_P4
  7  NC2  TRI  = V_DACR_IO
  8  VSS2  POWER  = GND
  9  NC3  TRI  = V_DACG_IO
  10  NC4  TRI  = V_DACB_IO

U36  74HC1G126GW  IC  pkg TSSOP5_0-65_2-05X1-25  page 29
  1  \1\  IN  = DEBUG_PORT_PRSNT
  2  \2\  IN  = DEBUG_PORT_UART_RX
  3  GND  POWER  = GND
  4  \4\  TRI  = SPA_SIN_SW_DBG
  5  \5\  POWER  = P3V3_AUX

U37  PCA9517ADP  IC  pkg SMLF  page 28
  1  VCCA  POWER  = P3V3_AUX
  2  SCLA  BI  = SMB_BMC_MM15_R1_SCL
  3  SDAA  BI  = SMB_BMC_MM15_R1_SDA
  4  GND  POWER  = GND
  5  ENABLE  BI  = DEBUG_PORT_PRSNT_BUF_EN
  6  SDAB  BI  = SMB_DEBUG_AUX_LVC3_USB_R1_SDA
  7  SCLB  BI  = SMB_DEBUG_AUX_LVC3_USB_R1_SCL
  8  VCCB  BI  = P3V3_AUX

U38  PRTR5V0U2X  IC  pkg SOT143XB  page 29
  1  GND  POWER  = GND
  2  IO1  BI  = USB2_01_F_DP
  3  IO2  BI  = USB2_01_F_DN
  4  VCC  POWER  = P5V_USB_REAR

U39  RT9059GQW  IC  pkg DFN10_THXE  page 53
  1  VOUT1  OUT  = P2V5_AUX
  2  VOUT2  OUT  = P2V5_AUX
  3  VOUT3  OUT  = P2V5_AUX
  4  ADJ  IN  = U39_ADJ
  5  PGOOD  OUT  = PWRGD_P2V5_AUX_R
  6  EN  IN  = PWRGD_P3V3_AUX_R2
  7  VIN1  IN  = P3V3_AUX
  8  VIN2  IN  = P3V3_AUX
  9  VIN3  IN  = P3V3_AUX
  10  VDD  IN  = P5V_AUX
  TH  EP  POWER  = GND
